(kicad_pcb
	(version 20260206)
	(generator "pcbnew")
	(generator_version "10.0")
	(general
		(thickness 1.6)
		(legacy_teardrops no)
	)
	(paper "A4")
	(title_block
		(title "Bryce Canyon_F.DPB_16315-1-OCP.brd")
		(comment 1 "Bryce Canyon / footprints 1727-1734 of 2223")
	)
	(layers
		(0 "F.Cu" signal "TOP")
		(4 "In1.Cu" signal "L2GND")
		(6 "In2.Cu" signal "L3")
		(8 "In3.Cu" signal "L4GND")
		(10 "In4.Cu" signal "L5")
		(12 "In5.Cu" signal "L6VCC")
		(14 "In6.Cu" signal "L7VCC")
		(16 "In7.Cu" signal "L8")
		(18 "In8.Cu" signal "L9GND")
		(20 "In9.Cu" signal "L10")
		(22 "In10.Cu" signal "L11GND")
		(2 "B.Cu" signal "BOTTOM")
		(9 "F.Adhes" user "F.Adhesive")
		(11 "B.Adhes" user "B.Adhesive")
		(13 "F.Paste" user "Package Geometry/Pastemask Top")
		(15 "B.Paste" user "Package Geometry/Pastemask Bottom")
		(5 "F.SilkS" user "Ref Des/Silkscreen Top")
		(7 "B.SilkS" user "Ref Des/Silkscreen Bottom")
		(1 "F.Mask" user "Board Geometry/Soldermask Top")
		(3 "B.Mask" user "Board Geometry/Soldermask Bottom")
		(17 "Dwgs.User" user "User.Drawings")
		(19 "Cmts.User" user "User.Comments")
		(21 "Eco1.User" user "User.Eco1")
		(23 "Eco2.User" user "User.Eco2")
		(25 "Edge.Cuts" user "Board Geometry/Outline")
		(27 "Margin" user)
		(31 "F.CrtYd" user "Package Geometry/Place Bound Top")
		(29 "B.CrtYd" user "Package Geometry/Place Bound Bottom")
		(35 "F.Fab" user "Ref Des/Assembly Top")
		(33 "B.Fab" user "Ref Des/Assembly Bottom")
	)
	(footprint ""
		(layer "F.Cu")
		(at 332.74 -164.596318 90)
		(property "Reference" "C282"
			(at 0 0 90)
			(layer "F.SilkS")
			(hide yes)
			(effects
				(font
					(size 1.27 1.27)
				)
			)
		)
		(property "Value" "SCD033U25V2KX-GP"
			(at 1.1811 -2.7051 90)
			(unlocked yes)
			(layer "F.Fab")
			(hide yes)
			(effects
				(font
					(size 1.016 1.016)
					(thickness 0.1524)
				)
			)
		)
		(property "Device Type" "C402H22"
			(at 1.1811 -4.2291 90)
			(unlocked yes)
			(layer "F.Fab")
			(hide yes)
			(effects
				(font
					(size 1.016 1.016)
					(thickness 0.1524)
				)
			)
		)
		(duplicate_pad_numbers_are_jumpers no)
		(fp_rect
			(start -0.4318 0.9525)
			(end 0.4318 -0.9525)
			(stroke
				(width 0)
				(type default)
			)
			(fill no)
			(layer "F.CrtYd")
		)
		(fp_rect
			(start -0.4318 0.9525)
			(end 0.4318 -0.9525)
			(stroke
				(width 0)
				(type default)
			)
			(fill no)
			(layer "F.Fab")
		)
		(pad "1" smd custom
			(at 0 -0.4445 90)
			(size 0.1524 0.1524)
			(layers "F.Cu" "F.Mask" "F.Paste")
			(net "SW_HDD_P18")
			(options
				(clearance outline)
				(anchor circle)
			)
			(primitives
				(gr_poly
					(pts
						(arc
							(start 0.3048 -0.2032)
							(mid 0.275042 -0.275042)
							(end 0.2032 -0.3048)
						)
						(arc
							(start -0.2032 -0.3048)
							(mid -0.275042 -0.275042)
							(end -0.3048 -0.2032)
						)
						(arc
							(start -0.3048 0.2032)
							(mid -0.275042 0.275042)
							(end -0.2032 0.3048)
						)
						(arc
							(start 0.2032 0.3048)
							(mid 0.275042 0.275042)
							(end 0.3048 0.2032)
						)
					)
					(width 0)
					(fill yes)
				)
			)
		)
		(pad "2" smd custom
			(at 0 0.4445 90)
			(size 0.1524 0.1524)
			(layers "F.Cu" "F.Mask" "F.Paste")
			(net "GND")
			(options
				(clearance outline)
				(anchor circle)
			)
			(primitives
				(gr_poly
					(pts
						(arc
							(start 0.3048 -0.2032)
							(mid 0.275042 -0.275042)
							(end 0.2032 -0.3048)
						)
						(arc
							(start -0.2032 -0.3048)
							(mid -0.275042 -0.275042)
							(end -0.3048 -0.2032)
						)
						(arc
							(start -0.3048 0.2032)
							(mid -0.275042 0.275042)
							(end -0.2032 0.3048)
						)
						(arc
							(start 0.2032 0.3048)
							(mid 0.275042 0.275042)
							(end 0.3048 0.2032)
						)
					)
					(width 0)
					(fill yes)
				)
			)
		)
	)
	(footprint ""
		(layer "F.Cu")
		(at 219.795344 -19.296888 -90)
		(property "Reference" "C531"
			(at 0 0 270)
			(layer "F.SilkS")
			(hide yes)
			(effects
				(font
					(size 1.27 1.27)
				)
			)
		)
		(property "Value" "SC2D2U25V5KX-2-GP"
			(at -0.0762 -6.1214 270)
			(unlocked yes)
			(layer "F.Fab")
			(hide yes)
			(effects
				(font
					(size 1.016 1.016)
					(thickness 0.1524)
				)
			)
		)
		(property "Device Type" "C805H54"
			(at -0.0762 -8.1534 270)
			(unlocked yes)
			(layer "F.Fab")
			(hide yes)
			(effects
				(font
					(size 1.016 1.016)
					(thickness 0.1524)
				)
			)
		)
		(duplicate_pad_numbers_are_jumpers no)
		(fp_line
			(start 0.635 0)
			(end -0.635 0)
			(stroke
				(width 0.508)
				(type default)
			)
			(layer "F.SilkS")
		)
		(fp_rect
			(start -0.9652 1.778)
			(end 0.9652 -1.778)
			(stroke
				(width 0)
				(type default)
			)
			(fill no)
			(layer "F.CrtYd")
		)
		(fp_poly
			(pts
				(xy -0.9652 -1.778) (xy 0.9652 -1.778) (xy 0.9652 1.778) (xy -0.9652 1.778)
			)
			(stroke
				(width 0)
				(type default)
			)
			(fill no)
			(layer "F.Fab")
		)
		(pad "1" smd rect
			(at 0 -0.9652 270)
			(size 1.397 1.143)
			(layers "F.Cu" "F.Mask" "F.Paste")
			(net "P12V_A_COMP")
		)
		(pad "2" smd rect
			(at 0 0.9652 270)
			(size 1.397 1.143)
			(layers "F.Cu" "F.Mask" "F.Paste")
			(net "GND")
		)
	)
	(footprint ""
		(layer "F.Cu")
		(at 413.512 -68.707)
		(property "Reference" "TP167"
			(at 0 0 0)
			(layer "F.SilkS")
			(hide yes)
			(effects
				(font
					(size 1.27 1.27)
				)
			)
		)
		(property "Value" "TPAD32-GP"
			(at -0.0508 -1.6764 0)
			(unlocked yes)
			(layer "F.Fab")
			(hide yes)
			(effects
				(font
					(size 1.016 1.016)
					(thickness 0.1524)
				)
			)
		)
		(property "Device Type" "TPAD32"
			(at -0.0508 -3.2004 0)
			(unlocked yes)
			(layer "F.Fab")
			(hide yes)
			(effects
				(font
					(size 1.016 1.016)
					(thickness 0.1524)
				)
			)
		)
		(duplicate_pad_numbers_are_jumpers no)
		(fp_poly
			(pts
				(arc
					(start 0.4064 0)
					(mid -0.4064 0)
					(end 0.4064 0)
				)
			)
			(stroke
				(width 0)
				(type default)
			)
			(fill no)
			(layer "F.CrtYd")
		)
		(fp_poly
			(pts
				(arc
					(start 0.7112 0)
					(mid -0.7112 0)
					(end 0.7112 0)
				)
			)
			(stroke
				(width 0)
				(type default)
			)
			(fill no)
			(layer "F.Fab")
		)
		(pad "1" smd circle
			(at 0 0)
			(size 0.8128 0.8128)
			(layers "F.Cu" "F.Mask" "F.Paste")
			(net "ACT_HDD_33")
		)
	)
	(footprint ""
		(layer "F.Cu")
		(at 444.1952 -248.8946 90)
		(property "Reference" "C631"
			(at 0 0 90)
			(layer "F.SilkS")
			(hide yes)
			(effects
				(font
					(size 1.27 1.27)
				)
			)
		)
		(property "Value" "SC10U16V5KX-7-GP-U"
			(at -0.0762 -6.1214 90)
			(unlocked yes)
			(layer "F.Fab")
			(hide yes)
			(effects
				(font
					(size 1.016 1.016)
					(thickness 0.1524)
				)
			)
		)
		(property "Device Type" "C805H58"
			(at -0.0762 -8.1534 90)
			(unlocked yes)
			(layer "F.Fab")
			(hide yes)
			(effects
				(font
					(size 1.016 1.016)
					(thickness 0.1524)
				)
			)
		)
		(duplicate_pad_numbers_are_jumpers no)
		(fp_line
			(start 0.635 0)
			(end -0.635 0)
			(stroke
				(width 0.508)
				(type default)
			)
			(layer "F.SilkS")
		)
		(fp_rect
			(start -0.9652 1.778)
			(end 0.9652 -1.778)
			(stroke
				(width 0)
				(type default)
			)
			(fill no)
			(layer "F.CrtYd")
		)
		(fp_poly
			(pts
				(xy -0.9652 -1.778) (xy 0.9652 -1.778) (xy 0.9652 1.778) (xy -0.9652 1.778)
			)
			(stroke
				(width 0)
				(type default)
			)
			(fill no)
			(layer "F.Fab")
		)
		(pad "1" smd rect
			(at 0 -0.9652 90)
			(size 1.397 1.143)
			(layers "F.Cu" "F.Mask" "F.Paste")
			(net "P12V_A_VIN_U22")
		)
		(pad "2" smd rect
			(at 0 0.9652 90)
			(size 1.397 1.143)
			(layers "F.Cu" "F.Mask" "F.Paste")
			(net "GND")
		)
	)
	(footprint ""
		(layer "F.Cu")
		(at 366.449102 -167.872918 -90)
		(property "Reference" "Q113"
			(at 0 0 270)
			(layer "F.SilkS")
			(hide yes)
			(effects
				(font
					(size 1.27 1.27)
				)
			)
		)
		(property "Value" "AO4406AL-GP"
			(at -3.707384 -1.5367 270)
			(unlocked yes)
			(layer "F.Fab")
			(hide yes)
			(effects
				(font
					(size 1.016 1.016)
					(thickness 0.1524)
				)
			)
		)
		(property "Device Type" "SOIC8H69"
			(at -3.707384 -3.0607 270)
			(unlocked yes)
			(layer "F.Fab")
			(hide yes)
			(effects
				(font
					(size 1.016 1.016)
					(thickness 0.1524)
				)
			)
		)
		(duplicate_pad_numbers_are_jumpers no)
		(fp_line
			(start -2.6289 3.4417)
			(end -2.6289 1.4732)
			(stroke
				(width 0.381)
				(type default)
			)
			(layer "F.SilkS")
		)
		(fp_line
			(start -2.7432 1.4224)
			(end -2.6416 1.4224)
			(stroke
				(width 0.1524)
				(type default)
			)
			(layer "F.SilkS")
		)
		(fp_line
			(start -2.7432 1.4224)
			(end 2.1336 1.4224)
			(stroke
				(width 0.1524)
				(type default)
			)
			(layer "F.SilkS")
		)
		(fp_line
			(start 2.1336 1.4224)
			(end 2.1336 -1.4224)
			(stroke
				(width 0.1524)
				(type default)
			)
			(layer "F.SilkS")
		)
		(fp_line
			(start -2.1844 -0.0508)
			(end -2.7178 0.508)
			(stroke
				(width 0.1524)
				(type default)
			)
			(layer "F.SilkS")
		)
		(fp_line
			(start -2.7178 -0.508)
			(end -2.1844 -0.0508)
			(stroke
				(width 0.1524)
				(type default)
			)
			(layer "F.SilkS")
		)
		(fp_line
			(start -2.7432 -1.4224)
			(end -2.7432 1.4224)
			(stroke
				(width 0.1524)
				(type default)
			)
			(layer "F.SilkS")
		)
		(fp_line
			(start 2.1336 -1.4224)
			(end -2.7432 -1.4224)
			(stroke
				(width 0.1524)
				(type default)
			)
			(layer "F.SilkS")
		)
		(fp_poly
			(pts
				(xy -2.2098 -1.4224) (xy -2.2098 1.4224) (xy 2.2098 1.4224) (xy 2.2098 -1.4224)
			)
			(stroke
				(width 0)
				(type default)
			)
			(fill yes)
			(layer "F.SilkS")
		)
		(fp_rect
			(start -2.450084 2.999994)
			(end 2.450084 -2.999994)
			(stroke
				(width 0)
				(type default)
			)
			(fill no)
			(layer "F.CrtYd")
		)
		(fp_poly
			(pts
				(xy -2.8194 3.6322) (xy -2.8194 -3.6322) (xy 2.8194 -3.6322) (xy 2.8194 1.18364) (xy 2.450084 1.18364)
				(xy 2.450084 -2.999994) (xy -2.450084 -2.999994) (xy -2.450084 2.999994) (xy 2.450084 2.999994)
				(xy 2.450084 1.18618) (xy 2.8194 1.18618) (xy 2.8194 3.6322)
			)
			(stroke
				(width 0)
				(type default)
			)
			(fill no)
			(layer "F.CrtYd")
		)
		(fp_rect
			(start -2.8194 3.6322)
			(end 2.8194 -3.6322)
			(stroke
				(width 0)
				(type default)
			)
			(fill no)
			(layer "F.Fab")
		)
		(pad "1" smd rect
			(at -1.905 2.54 270)
			(size 0.635 1.651)
			(layers "F.Cu" "F.Mask" "F.Paste")
			(net "P5V_HDD19")
		)
		(pad "2" smd rect
			(at -0.635 2.54 270)
			(size 0.635 1.651)
			(layers "F.Cu" "F.Mask" "F.Paste")
			(net "P5V_HDD19")
		)
		(pad "3" smd rect
			(at 0.635 2.54 270)
			(size 0.635 1.651)
			(layers "F.Cu" "F.Mask" "F.Paste")
			(net "P5V_HDD19")
		)
		(pad "4" smd rect
			(at 1.905 2.54 270)
			(size 0.635 1.651)
			(layers "F.Cu" "F.Mask" "F.Paste")
			(net "SW_HDD_P19")
		)
		(pad "5" smd rect
			(at 1.905 -2.54 270)
			(size 0.635 1.651)
			(layers "F.Cu" "F.Mask" "F.Paste")
			(net "P5V_A_3")
		)
		(pad "6" smd rect
			(at 0.635 -2.54 270)
			(size 0.635 1.651)
			(layers "F.Cu" "F.Mask" "F.Paste")
			(net "P5V_A_3")
		)
		(pad "7" smd rect
			(at -0.635 -2.54 270)
			(size 0.635 1.651)
			(layers "F.Cu" "F.Mask" "F.Paste")
			(net "P5V_A_3")
		)
		(pad "8" smd rect
			(at -1.905 -2.54 270)
			(size 0.635 1.651)
			(layers "F.Cu" "F.Mask" "F.Paste")
			(net "P5V_A_3")
		)
	)
	(footprint ""
		(layer "F.Cu")
		(at 334.03921 -33.5534 180)
		(property "Reference" "R1299"
			(at 0 0 180)
			(layer "F.SilkS")
			(hide yes)
			(effects
				(font
					(size 1.27 1.27)
				)
			)
		)
		(property "Value" "2K2R2F-GP"
			(at 0.064008 -3.993896 180)
			(unlocked yes)
			(layer "F.Fab")
			(hide yes)
			(effects
				(font
					(size 1.016 1.016)
					(thickness 0.1524)
				)
			)
		)
		(property "Device Type" "R402H16"
			(at 0.064008 -5.517896 180)
			(unlocked yes)
			(layer "F.Fab")
			(hide yes)
			(effects
				(font
					(size 1.016 1.016)
					(thickness 0.1524)
				)
			)
		)
		(duplicate_pad_numbers_are_jumpers no)
		(fp_line
			(start 0.508 -0.9398)
			(end -0.508 -0.9398)
			(stroke
				(width 0.1524)
				(type default)
			)
			(layer "F.SilkS")
		)
		(fp_line
			(start -0.508 -0.9398)
			(end -0.508 0.9398)
			(stroke
				(width 0.1524)
				(type default)
			)
			(layer "F.SilkS")
		)
		(fp_rect
			(start -0.508 0.9398)
			(end 0.508 -0.9398)
			(stroke
				(width 0)
				(type default)
			)
			(fill no)
			(layer "F.CrtYd")
		)
		(fp_rect
			(start -0.508 0.9398)
			(end 0.508 -0.9398)
			(stroke
				(width 0)
				(type default)
			)
			(fill no)
			(layer "F.Fab")
		)
		(pad "1" smd custom
			(at 0 -0.4445 180)
			(size 0.1397 0.1397)
			(layers "F.Cu" "F.Mask" "F.Paste")
			(net "P3V3_STBY_B")
			(options
				(clearance outline)
				(anchor circle)
			)
			(primitives
				(gr_poly
					(pts
						(arc
							(start -0.1778 -0.2794)
							(mid -0.249642 -0.249642)
							(end -0.2794 -0.1778)
						)
						(arc
							(start -0.2794 0.1778)
							(mid -0.249642 0.249642)
							(end -0.1778 0.2794)
						)
						(arc
							(start 0.1778 0.2794)
							(mid 0.249642 0.249642)
							(end 0.2794 0.1778)
						)
						(arc
							(start 0.2794 -0.1778)
							(mid 0.249642 -0.249642)
							(end 0.1778 -0.2794)
						)
					)
					(width 0)
					(fill yes)
				)
			)
		)
		(pad "2" smd custom
			(at 0 0.4445 180)
			(size 0.1397 0.1397)
			(layers "F.Cu" "F.Mask" "F.Paste")
			(net "I2C_BMC_B_MISC_SDA")
			(options
				(clearance outline)
				(anchor circle)
			)
			(primitives
				(gr_poly
					(pts
						(arc
							(start -0.1778 -0.2794)
							(mid -0.249642 -0.249642)
							(end -0.2794 -0.1778)
						)
						(arc
							(start -0.2794 0.1778)
							(mid -0.249642 0.249642)
							(end -0.1778 0.2794)
						)
						(arc
							(start 0.1778 0.2794)
							(mid 0.249642 0.249642)
							(end 0.2794 0.1778)
						)
						(arc
							(start 0.2794 -0.1778)
							(mid 0.249642 -0.249642)
							(end 0.1778 -0.2794)
						)
					)
					(width 0)
					(fill yes)
				)
			)
		)
	)
	(footprint ""
		(layer "F.Cu")
		(at 97.497646 -304.353468 180)
		(property "Reference" "R233"
			(at 0 0 180)
			(layer "F.SilkS")
			(hide yes)
			(effects
				(font
					(size 1.27 1.27)
				)
			)
		)
		(property "Value" "91R3F-1-GP"
			(at -0.0254 -2.5146 180)
			(unlocked yes)
			(layer "F.Fab")
			(hide yes)
			(effects
				(font
					(size 1.016 1.016)
					(thickness 0.1524)
				)
			)
		)
		(property "Device Type" "R603H22"
			(at -0.0254 -4.0386 180)
			(unlocked yes)
			(layer "F.Fab")
			(hide yes)
			(effects
				(font
					(size 1.016 1.016)
					(thickness 0.1524)
				)
			)
		)
		(duplicate_pad_numbers_are_jumpers no)
		(fp_line
			(start 0.2032 0)
			(end 0.4826 0)
			(stroke
				(width 0.2032)
				(type default)
			)
			(layer "F.SilkS")
		)
		(fp_line
			(start -0.4826 0)
			(end -0.2032 0)
			(stroke
				(width 0.2032)
				(type default)
			)
			(layer "F.SilkS")
		)
		(fp_rect
			(start -0.5842 1.3335)
			(end 0.5842 -1.3335)
			(stroke
				(width 0)
				(type default)
			)
			(fill no)
			(layer "F.CrtYd")
		)
		(fp_rect
			(start -0.5842 1.3335)
			(end 0.5842 -1.3335)
			(stroke
				(width 0)
				(type default)
			)
			(fill no)
			(layer "F.Fab")
		)
		(pad "1" smd custom
			(at 0 -0.762 180)
			(size 0.2159 0.2159)
			(layers "F.Cu" "F.Mask" "F.Paste")
			(net "P5V_B")
			(options
				(clearance outline)
				(anchor circle)
			)
			(primitives
				(gr_poly
					(pts
						(arc
							(start -0.3302 -0.4318)
							(mid -0.402042 -0.402042)
							(end -0.4318 -0.3302)
						)
						(arc
							(start -0.4318 0.3302)
							(mid -0.402042 0.402042)
							(end -0.3302 0.4318)
						)
						(arc
							(start 0.3302 0.4318)
							(mid 0.402042 0.402042)
							(end 0.4318 0.3302)
						)
						(arc
							(start 0.4318 -0.3302)
							(mid 0.402042 -0.402042)
							(end 0.3302 -0.4318)
						)
					)
					(width 0)
					(fill yes)
				)
			)
		)
		(pad "2" smd custom
			(at 0 0.762 180)
			(size 0.2159 0.2159)
			(layers "F.Cu" "F.Mask" "F.Paste")
			(net "DRV_ACT_27")
			(options
				(clearance outline)
				(anchor circle)
			)
			(primitives
				(gr_poly
					(pts
						(arc
							(start -0.3302 -0.4318)
							(mid -0.402042 -0.402042)
							(end -0.4318 -0.3302)
						)
						(arc
							(start -0.4318 0.3302)
							(mid -0.402042 0.402042)
							(end -0.3302 0.4318)
						)
						(arc
							(start 0.3302 0.4318)
							(mid 0.402042 0.402042)
							(end 0.4318 0.3302)
						)
						(arc
							(start 0.4318 -0.3302)
							(mid 0.402042 -0.402042)
							(end 0.3302 -0.4318)
						)
					)
					(width 0)
					(fill yes)
				)
			)
		)
	)
	(footprint ""
		(layer "F.Cu")
		(at 353.184714 -158.660592 -90)
		(property "Reference" "C286"
			(at 0 0 270)
			(layer "F.SilkS")
			(hide yes)
			(effects
				(font
					(size 1.27 1.27)
				)
			)
		)
		(property "Value" "SCD01U16V1KX-GP"
			(at -2.8321 -1.7399 270)
			(unlocked yes)
			(layer "F.Fab")
			(hide yes)
			(effects
				(font
					(size 1.016 1.016)
					(thickness 0.1524)
				)
			)
		)
		(property "Device Type" "C0201H13"
			(at -2.8321 -3.2639 270)
			(unlocked yes)
			(layer "F.Fab")
			(hide yes)
			(effects
				(font
					(size 1.016 1.016)
					(thickness 0.1524)
				)
			)
		)
		(duplicate_pad_numbers_are_jumpers no)
		(fp_rect
			(start -0.2794 0.6477)
			(end 0.2794 -0.6477)
			(stroke
				(width 0)
				(type default)
			)
			(fill no)
			(layer "F.CrtYd")
		)
		(fp_rect
			(start -0.2794 0.6477)
			(end 0.2794 -0.6477)
			(stroke
				(width 0)
				(type default)
			)
			(fill no)
			(layer "F.Fab")
		)
		(pad "1" smd custom
			(at 0 -0.2794 270)
			(size 0.0762 0.0762)
			(layers "F.Cu" "F.Mask" "F.Paste")
			(net "SAS_HDD_RX_P19")
			(options
				(clearance outline)
				(anchor circle)
			)
			(primitives
				(gr_poly
					(pts
						(arc
							(start 0.1524 -0.127)
							(mid 0.137521 -0.162921)
							(end 0.1016 -0.1778)
						)
						(arc
							(start -0.1016 -0.1778)
							(mid -0.137521 -0.162921)
							(end -0.1524 -0.127)
						)
						(arc
							(start -0.1524 0.127)
							(mid -0.137521 0.162921)
							(end -0.1016 0.1778)
						)
						(arc
							(start 0.1016 0.1778)
							(mid 0.137521 0.162921)
							(end 0.1524 0.127)
						)
					)
					(width 0)
					(fill yes)
				)
			)
		)
		(pad "2" smd custom
			(at 0 0.2794 270)
			(size 0.0762 0.0762)
			(layers "F.Cu" "F.Mask" "F.Paste")
			(net "PHY_SCC_A_TO_DRV_A_19_DP")
			(options
				(clearance outline)
				(anchor circle)
			)
			(primitives
				(gr_poly
					(pts
						(arc
							(start 0.1524 -0.127)
							(mid 0.137521 -0.162921)
							(end 0.1016 -0.1778)
						)
						(arc
							(start -0.1016 -0.1778)
							(mid -0.137521 -0.162921)
							(end -0.1524 -0.127)
						)
						(arc
							(start -0.1524 0.127)
							(mid -0.137521 0.162921)
							(end -0.1016 0.1778)
						)
						(arc
							(start 0.1016 0.1778)
							(mid 0.137521 0.162921)
							(end 0.1524 0.127)
						)
					)
					(width 0)
					(fill yes)
				)
			)
		)
	)
)
